# SCM (Grand Teton) — schematic netlist excerpt (pin names and nets, part order shuffled) for the footprints in the layout excerpt that follows; sources: Cadence DE-HDL packaged netlist, KiCad conversion of 12092022_DA0F0TMDCD0_F0T_Management_Board_D_brd_V3_OCP.brd

R459  Q_RES  33.2 1% CHIP  pkg 0402LF  page 34 : A = BSM_PRSNT_R_N ; B = BSM_PRSNT_R1_N
R356  Q_RES  120 1% CHIP  pkg 0402LF  page 20 : A = M_BMC_DDR4_MA<5> ; B = P1V2_AUX

(kicad_pcb
	(version 20260206)
	(generator "pcbnew")
	(generator_version "10.0")
	(general
		(thickness 1.6)
		(legacy_teardrops no)
	)
	(paper "A4")
	(title_block
		(title "12092022_DA0F0TMDCD0_F0T_Management_Board_D_brd_V3_OCP.brd")
		(comment 1 "Grand Teton / footprints 978-979 of 1440")
	)
	(layers
		(0 "F.Cu" signal "TOP")
		(4 "In1.Cu" signal "GND")
		(6 "In2.Cu" signal "IN1")
		(8 "In3.Cu" signal "GND1")
		(10 "In4.Cu" signal "IN2")
		(12 "In5.Cu" signal "VCC")
		(14 "In6.Cu" signal "VCC1")
		(16 "In7.Cu" signal "IN3")
		(18 "In8.Cu" signal "GND2")
		(20 "In9.Cu" signal "IN4")
		(22 "In10.Cu" signal "GND3")
		(2 "B.Cu" signal "BOTTOM")
		(9 "F.Adhes" user "F.Adhesive")
		(11 "B.Adhes" user "B.Adhesive")
		(13 "F.Paste" user "Package Geometry/Pastemask Top")
		(15 "B.Paste" user "Package Geometry/Pastemask Bottom")
		(5 "F.SilkS" user "Ref Des/Silkscreen Top")
		(7 "B.SilkS" user "Ref Des/Silkscreen Bottom")
		(1 "F.Mask" user "Board Geometry/Soldermask Top")
		(3 "B.Mask" user "Board Geometry/Soldermask Bottom")
		(17 "Dwgs.User" user "User.Drawings")
		(19 "Cmts.User" user "User.Comments")
		(21 "Eco1.User" user "User.Eco1")
		(23 "Eco2.User" user "User.Eco2")
		(25 "Edge.Cuts" user "Board Geometry/Outline")
		(27 "Margin" user)
		(31 "F.CrtYd" user "Package Geometry/Place Bound Top")
		(29 "B.CrtYd" user "Package Geometry/Place Bound Bottom")
		(35 "F.Fab" user "Ref Des/Assembly Top")
		(33 "B.Fab" user "Ref Des/Assembly Bottom")
	)
	(footprint ""
		(layer "B.Cu")
		(at 85.29955 -45.443394 180)
		(property "Reference" "R356"
			(at 0 0 0)
			(layer "B.SilkS")
			(hide yes)
			(effects
				(font
					(size 1.27 1.27)
				)
				(justify mirror)
			)
		)
		(property "Value" ""
			(at 0 0 0)
			(layer "B.Fab")
			(effects
				(font
					(size 1.27 1.27)
				)
				(justify mirror)
			)
		)
		(duplicate_pad_numbers_are_jumpers no)
		(fp_line
			(start 0.7874 0.4064)
			(end 0.7874 -0.4064)
			(stroke
				(width 0.1524)
				(type default)
			)
			(layer "B.SilkS")
		)
		(fp_line
			(start 0.7874 -0.4064)
			(end -0.7874 -0.4064)
			(stroke
				(width 0.1524)
				(type default)
			)
			(layer "B.SilkS")
		)
		(fp_line
			(start -0.7874 0.4064)
			(end 0.7874 0.4064)
			(stroke
				(width 0.1524)
				(type default)
			)
			(layer "B.SilkS")
		)
		(fp_line
			(start -0.7874 -0.4064)
			(end -0.7874 0.4064)
			(stroke
				(width 0.1524)
				(type default)
			)
			(layer "B.SilkS")
		)
		(fp_line
			(start 0.67945 0.3048)
			(end 0.67945 -0.305054)
			(stroke
				(width 0.1)
				(type default)
			)
			(layer "B.Fab")
		)
		(fp_line
			(start 0.67945 -0.305054)
			(end 0.12065 -0.305054)
			(stroke
				(width 0.1)
				(type default)
			)
			(layer "B.Fab")
		)
		(fp_line
			(start 0.12065 0.3048)
			(end 0.67945 0.3048)
			(stroke
				(width 0.1)
				(type default)
			)
			(layer "B.Fab")
		)
		(fp_line
			(start 0.12065 0.2794)
			(end 0.12065 0.3048)
			(stroke
				(width 0.1)
				(type default)
			)
			(layer "B.Fab")
		)
		(fp_line
			(start 0.12065 -0.2794)
			(end -0.12065 -0.2794)
			(stroke
				(width 0.1)
				(type default)
			)
			(layer "B.Fab")
		)
		(fp_line
			(start 0.12065 -0.305054)
			(end 0.12065 -0.2794)
			(stroke
				(width 0.1)
				(type default)
			)
			(layer "B.Fab")
		)
		(fp_line
			(start -0.120396 0.3048)
			(end -0.120396 0.2794)
			(stroke
				(width 0.1)
				(type default)
			)
			(layer "B.Fab")
		)
		(fp_line
			(start -0.120396 0.2794)
			(end 0.12065 0.2794)
			(stroke
				(width 0.1)
				(type default)
			)
			(layer "B.Fab")
		)
		(fp_line
			(start -0.12065 -0.2794)
			(end -0.12065 -0.3048)
			(stroke
				(width 0.1)
				(type default)
			)
			(layer "B.Fab")
		)
		(fp_line
			(start -0.12065 -0.3048)
			(end -0.67945 -0.3048)
			(stroke
				(width 0.1)
				(type default)
			)
			(layer "B.Fab")
		)
		(fp_line
			(start -0.67945 0.3048)
			(end -0.120396 0.3048)
			(stroke
				(width 0.1)
				(type default)
			)
			(layer "B.Fab")
		)
		(fp_line
			(start -0.67945 -0.3048)
			(end -0.67945 0.3048)
			(stroke
				(width 0.1)
				(type default)
			)
			(layer "B.Fab")
		)
		(pad "1" smd circle
			(at 0.40005 0)
			(size 0 0)
			(layers "B.Cu" "B.Mask" "B.Paste")
			(net "M_BMC_DDR4_MA<5>")
		)
		(pad "2" smd circle
			(at -0.40005 0)
			(size 0 0)
			(layers "B.Cu" "B.Mask" "B.Paste")
			(net "P1V2_AUX")
		)
	)
	(footprint ""
		(layer "B.Cu")
		(at 27.31135 -86.778846)
		(property "Reference" "R459"
			(at 0 0 0)
			(layer "B.SilkS")
			(hide yes)
			(effects
				(font
					(size 1.27 1.27)
				)
				(justify mirror)
			)
		)
		(property "Value" ""
			(at 0 0 0)
			(layer "B.Fab")
			(effects
				(font
					(size 1.27 1.27)
				)
				(justify mirror)
			)
		)
		(duplicate_pad_numbers_are_jumpers no)
		(fp_line
			(start -0.7874 -0.4064)
			(end -0.7874 0.4064)
			(stroke
				(width 0.1524)
				(type default)
			)
			(layer "B.SilkS")
		)
		(fp_line
			(start -0.7874 0.4064)
			(end 0.7874 0.4064)
			(stroke
				(width 0.1524)
				(type default)
			)
			(layer "B.SilkS")
		)
		(fp_line
			(start 0.7874 -0.4064)
			(end -0.7874 -0.4064)
			(stroke
				(width 0.1524)
				(type default)
			)
			(layer "B.SilkS")
		)
		(fp_line
			(start 0.7874 0.4064)
			(end 0.7874 -0.4064)
			(stroke
				(width 0.1524)
				(type default)
			)
			(layer "B.SilkS")
		)
		(fp_line
			(start -0.67945 -0.3048)
			(end -0.67945 0.3048)
			(stroke
				(width 0.1)
				(type default)
			)
			(layer "B.Fab")
		)
		(fp_line
			(start -0.67945 0.3048)
			(end -0.120396 0.3048)
			(stroke
				(width 0.1)
				(type default)
			)
			(layer "B.Fab")
		)
		(fp_line
			(start -0.12065 -0.3048)
			(end -0.67945 -0.3048)
			(stroke
				(width 0.1)
				(type default)
			)
			(layer "B.Fab")
		)
		(fp_line
			(start -0.12065 -0.2794)
			(end -0.12065 -0.3048)
			(stroke
				(width 0.1)
				(type default)
			)
			(layer "B.Fab")
		)
		(fp_line
			(start -0.120396 0.2794)
			(end 0.12065 0.2794)
			(stroke
				(width 0.1)
				(type default)
			)
			(layer "B.Fab")
		)
		(fp_line
			(start -0.120396 0.3048)
			(end -0.120396 0.2794)
			(stroke
				(width 0.1)
				(type default)
			)
			(layer "B.Fab")
		)
		(fp_line
			(start 0.12065 -0.305054)
			(end 0.12065 -0.2794)
			(stroke
				(width 0.1)
				(type default)
			)
			(layer "B.Fab")
		)
		(fp_line
			(start 0.12065 -0.2794)
			(end -0.12065 -0.2794)
			(stroke
				(width 0.1)
				(type default)
			)
			(layer "B.Fab")
		)
		(fp_line
			(start 0.12065 0.2794)
			(end 0.12065 0.3048)
			(stroke
				(width 0.1)
				(type default)
			)
			(layer "B.Fab")
		)
		(fp_line
			(start 0.12065 0.3048)
			(end 0.67945 0.3048)
			(stroke
				(width 0.1)
				(type default)
			)
			(layer "B.Fab")
		)
		(fp_line
			(start 0.67945 -0.305054)
			(end 0.12065 -0.305054)
			(stroke
				(width 0.1)
				(type default)
			)
			(layer "B.Fab")
		)
		(fp_line
			(start 0.67945 0.3048)
			(end 0.67945 -0.305054)
			(stroke
				(width 0.1)
				(type default)
			)
			(layer "B.Fab")
		)
		(pad "1" smd circle
			(at 0.40005 0 180)
			(size 0 0)
			(layers "B.Cu" "B.Mask" "B.Paste")
			(net "BSM_PRSNT_R_N")
		)
		(pad "2" smd circle
			(at -0.40005 0 180)
			(size 0 0)
			(layers "B.Cu" "B.Mask" "B.Paste")
			(net "BSM_PRSNT_R1_N")
		)
	)
)
